(kicad_pcb
	(version 20260206)
	(generator "pcbnew")
	(generator_version "10.0")
	(general
		(thickness 1.6)
		(legacy_teardrops no)
	)
	(paper "A4")
	(title_block
		(title "panther-plus-userver — 13130-1b_20150205.brd")
		(comment 1 "Honey Badger (Wiwynn) / footprint 624 of 1509 (DIMM4), pads 177-183 of 210")
	)
	(layers
		(0 "F.Cu" signal "TOP")
		(4 "In1.Cu" signal "L2")
		(6 "In2.Cu" signal "L3")
		(8 "In3.Cu" signal "L4")
		(10 "In4.Cu" signal "L5")
		(12 "In5.Cu" signal "L6")
		(14 "In6.Cu" signal "L7")
		(16 "In7.Cu" signal "L8")
		(18 "In8.Cu" signal "L9")
		(20 "In9.Cu" signal "L10")
		(22 "In10.Cu" signal "L11")
		(2 "B.Cu" signal "BOTTOM")
		(9 "F.Adhes" user "F.Adhesive")
		(11 "B.Adhes" user "B.Adhesive")
		(13 "F.Paste" user "Package Geometry/Pastemask Top")
		(15 "B.Paste" user "Package Geometry/Pastemask Bottom")
		(5 "F.SilkS" user "Ref Des/Silkscreen Top")
		(7 "B.SilkS" user "Ref Des/Silkscreen Bottom")
		(1 "F.Mask" user "Board Geometry/Soldermask Top")
		(3 "B.Mask" user "Board Geometry/Soldermask Bottom")
		(17 "Dwgs.User" user "User.Drawings")
		(19 "Cmts.User" user "User.Comments")
		(21 "Eco1.User" user "User.Eco1")
		(23 "Eco2.User" user "User.Eco2")
		(25 "Edge.Cuts" user "Board Geometry/Outline")
		(27 "Margin" user)
		(31 "F.CrtYd" user "Package Geometry/Place Bound Top")
		(29 "B.CrtYd" user "Package Geometry/Place Bound Bottom")
		(35 "F.Fab" user "Ref Des/Assembly Top")
		(33 "B.Fab" user "Ref Des/Assembly Bottom")
	)
	(footprint ""
		(layer "F.Cu")
		(at 159.999934 -5.790692)
		(property "Reference" "DIMM4"
			(at 0 0 0)
			(layer "F.SilkS")
			(hide yes)
			(effects
				(font
					(size 1.27 1.27)
				)
			)
		)
		(property "Value" "DDR3-204P-174-COLAY-1-GP"
			(at -40.682164 -17.468088 0)
			(unlocked yes)
			(layer "F.Fab")
			(hide yes)
			(effects
				(font
					(size 1.016 1.016)
					(thickness 0.1524)
				)
			)
		)
		(property "Device Type" "AS0A626-H8SN-7H-COLAY-1"
			(at -40.682164 -18.992088 0)
			(unlocked yes)
			(layer "F.Fab")
			(hide yes)
			(effects
				(font
					(size 1.016 1.016)
					(thickness 0.1524)
				)
			)
		)
		(duplicate_pad_numbers_are_jumpers no)
		(pad "175" smd custom
			(at 22.949916 4.106672)
			(size 0.1143 0.1143)
			(layers "F.Cu" "F.Mask" "F.Paste")
			(net "GND")
			(options
				(clearance outline)
				(anchor circle)
			)
			(primitives
				(gr_poly
					(pts
						(xy 0 0.9017) (xy -0.03175 0.89916) (xy -0.0635 0.889) (xy -0.09144 0.87376) (xy -0.11684 0.85344)
						(xy -0.13716 0.82804) (xy -0.1524 0.8001) (xy -0.16256 0.76835) (xy -0.1651 0.7366) (xy -0.1651 0.11938)
						(xy -0.17272 0.11176) (xy -0.19812 0.0762) (xy -0.2032 0.06604) (xy -0.20701 0.05715) (xy -0.21209 0.04699)
						(xy -0.2159 0.03683) (xy -0.21844 0.02667) (xy -0.22225 0.01524) (xy -0.22352 0.00508) (xy -0.22606 -0.00508)
						(xy -0.22733 -0.01651) (xy -0.22733 -0.02667) (xy -0.2286 -0.0381) (xy -0.22733 -0.04953) (xy -0.22733 -0.05969)
						(xy -0.22606 -0.07112) (xy -0.22352 -0.08128) (xy -0.22225 -0.09144) (xy -0.21844 -0.10287) (xy -0.2159 -0.11303)
						(xy -0.21209 -0.12319) (xy -0.20701 -0.13335) (xy -0.2032 -0.14224) (xy -0.19812 -0.1524) (xy -0.17272 -0.18796)
						(xy -0.1651 -0.19558) (xy -0.1651 -0.7366) (xy -0.16256 -0.76835) (xy -0.1524 -0.8001) (xy -0.13716 -0.82804)
						(xy -0.11684 -0.85344) (xy -0.09144 -0.87376) (xy -0.0635 -0.889) (xy -0.03175 -0.89916) (xy 0 -0.9017)
						(xy 0.03175 -0.89916) (xy 0.0635 -0.889) (xy 0.09144 -0.87376) (xy 0.11684 -0.85344) (xy 0.13716 -0.82804)
						(xy 0.1524 -0.8001) (xy 0.16256 -0.76835) (xy 0.1651 -0.7366) (xy 0.1651 -0.19685) (xy 0.17272 -0.18923)
						(xy 0.17907 -0.18034) (xy 0.18669 -0.17145) (xy 0.19177 -0.16256) (xy 0.19812 -0.15367) (xy 0.20828 -0.13335)
						(xy 0.21971 -0.10287) (xy 0.22225 -0.09271) (xy 0.22479 -0.08128) (xy 0.22606 -0.07112) (xy 0.2286 -0.05969)
						(xy 0.2286 -0.01651) (xy 0.22606 -0.00508) (xy 0.22479 0.00508) (xy 0.22225 0.01651) (xy 0.21971 0.02667)
						(xy 0.20828 0.05715) (xy 0.19812 0.07747) (xy 0.19177 0.08636) (xy 0.18669 0.09525) (xy 0.17907 0.10414)
						(xy 0.17272 0.11303) (xy 0.1651 0.12065) (xy 0.1651 0.7366) (xy 0.16256 0.76835) (xy 0.1524 0.8001)
						(xy 0.13716 0.82804) (xy 0.11684 0.85344) (xy 0.09144 0.87376) (xy 0.0635 0.889) (xy 0.03175 0.89916)
					)
					(width 0)
					(fill yes)
				)
			)
		)
		(pad "176" smd custom
			(at 23.24989 -4.106672)
			(size 0.1143 0.1143)
			(layers "F.Cu" "F.Mask" "F.Paste")
			(net "M_B_DQ51")
			(options
				(clearance outline)
				(anchor circle)
			)
			(primitives
				(gr_poly
					(pts
						(xy 0 0.9017) (xy -0.03175 0.89916) (xy -0.0635 0.889) (xy -0.09144 0.87376) (xy -0.11684 0.85344)
						(xy -0.13716 0.82804) (xy -0.1524 0.8001) (xy -0.16256 0.76835) (xy -0.1651 0.7366) (xy -0.1651 0.19685)
						(xy -0.17272 0.18923) (xy -0.17907 0.18034) (xy -0.18669 0.17145) (xy -0.19177 0.16256) (xy -0.19812 0.15367)
						(xy -0.20828 0.13335) (xy -0.21971 0.10287) (xy -0.22225 0.09271) (xy -0.22479 0.08128) (xy -0.22606 0.07112)
						(xy -0.2286 0.05969) (xy -0.2286 0.01651) (xy -0.22606 0.00508) (xy -0.22479 -0.00508) (xy -0.22225 -0.01651)
						(xy -0.21971 -0.02667) (xy -0.20828 -0.05715) (xy -0.19812 -0.07747) (xy -0.19177 -0.08636) (xy -0.18669 -0.09525)
						(xy -0.17907 -0.10414) (xy -0.17272 -0.11303) (xy -0.1651 -0.12065) (xy -0.1651 -0.7366) (xy -0.16256 -0.76835)
						(xy -0.1524 -0.8001) (xy -0.13716 -0.82804) (xy -0.11684 -0.85344) (xy -0.09144 -0.87376) (xy -0.0635 -0.889)
						(xy -0.03175 -0.89916) (xy 0 -0.9017) (xy 0.03175 -0.89916) (xy 0.0635 -0.889) (xy 0.09144 -0.87376)
						(xy 0.11684 -0.85344) (xy 0.13716 -0.82804) (xy 0.1524 -0.8001) (xy 0.16256 -0.76835) (xy 0.1651 -0.7366)
						(xy 0.1651 -0.11938) (xy 0.17272 -0.11176) (xy 0.19812 -0.0762) (xy 0.2032 -0.06604) (xy 0.20701 -0.05715)
						(xy 0.21209 -0.04699) (xy 0.2159 -0.03683) (xy 0.21844 -0.02667) (xy 0.22225 -0.01524) (xy 0.22352 -0.00508)
						(xy 0.22606 0.00508) (xy 0.22733 0.01651) (xy 0.22733 0.02667) (xy 0.2286 0.0381) (xy 0.22733 0.04953)
						(xy 0.22733 0.05969) (xy 0.22606 0.07112) (xy 0.22352 0.08128) (xy 0.22225 0.09144) (xy 0.21844 0.10287)
						(xy 0.2159 0.11303) (xy 0.21209 0.12319) (xy 0.20701 0.13335) (xy 0.2032 0.14224) (xy 0.19812 0.1524)
						(xy 0.17272 0.18796) (xy 0.1651 0.19558) (xy 0.1651 0.7366) (xy 0.16256 0.76835) (xy 0.1524 0.8001)
						(xy 0.13716 0.82804) (xy 0.11684 0.85344) (xy 0.09144 0.87376) (xy 0.0635 0.889) (xy 0.03175 0.89916)
					)
					(width 0)
					(fill yes)
				)
			)
		)
		(pad "177" smd custom
			(at 23.550118 4.106672)
			(size 0.1143 0.1143)
			(layers "F.Cu" "F.Mask" "F.Paste")
			(net "M_B_DQ54")
			(options
				(clearance outline)
				(anchor circle)
			)
			(primitives
				(gr_poly
					(pts
						(xy 0 0.9017) (xy -0.03175 0.89916) (xy -0.0635 0.889) (xy -0.09144 0.87376) (xy -0.11684 0.85344)
						(xy -0.13716 0.82804) (xy -0.1524 0.8001) (xy -0.16256 0.76835) (xy -0.1651 0.7366) (xy -0.1651 -0.13462)
						(xy -0.17272 -0.14224) (xy -0.19812 -0.1778) (xy -0.2032 -0.18796) (xy -0.20701 -0.19685) (xy -0.21209 -0.20701)
						(xy -0.2159 -0.21717) (xy -0.21844 -0.22733) (xy -0.22225 -0.23876) (xy -0.22352 -0.24892) (xy -0.22606 -0.25908)
						(xy -0.22733 -0.27051) (xy -0.22733 -0.28067) (xy -0.2286 -0.2921) (xy -0.22733 -0.30353) (xy -0.22733 -0.31369)
						(xy -0.22606 -0.32512) (xy -0.22352 -0.33528) (xy -0.22225 -0.34544) (xy -0.21844 -0.35687) (xy -0.2159 -0.36703)
						(xy -0.21209 -0.37719) (xy -0.20701 -0.38735) (xy -0.2032 -0.39624) (xy -0.19812 -0.4064) (xy -0.17272 -0.44196)
						(xy -0.1651 -0.44958) (xy -0.1651 -0.7366) (xy -0.16256 -0.76835) (xy -0.1524 -0.8001) (xy -0.13716 -0.82804)
						(xy -0.11684 -0.85344) (xy -0.09144 -0.87376) (xy -0.0635 -0.889) (xy -0.03175 -0.89916) (xy 0 -0.9017)
						(xy 0.03175 -0.89916) (xy 0.0635 -0.889) (xy 0.09144 -0.87376) (xy 0.11684 -0.85344) (xy 0.13716 -0.82804)
						(xy 0.1524 -0.8001) (xy 0.16256 -0.76835) (xy 0.1651 -0.7366) (xy 0.1651 -0.44958) (xy 0.17272 -0.44196)
						(xy 0.19812 -0.4064) (xy 0.2032 -0.39624) (xy 0.20701 -0.38735) (xy 0.21209 -0.37719) (xy 0.2159 -0.36703)
						(xy 0.21844 -0.35687) (xy 0.22225 -0.34544) (xy 0.22352 -0.33528) (xy 0.22606 -0.32512) (xy 0.22733 -0.31369)
						(xy 0.22733 -0.30353) (xy 0.2286 -0.2921) (xy 0.22733 -0.28067) (xy 0.22733 -0.27051) (xy 0.22606 -0.25908)
						(xy 0.22352 -0.24892) (xy 0.22225 -0.23876) (xy 0.21844 -0.22733) (xy 0.2159 -0.21717) (xy 0.21209 -0.20701)
						(xy 0.20701 -0.19685) (xy 0.2032 -0.18796) (xy 0.19812 -0.1778) (xy 0.17272 -0.14224) (xy 0.1651 -0.13462)
						(xy 0.1651 0.7366) (xy 0.16256 0.76835) (xy 0.1524 0.8001) (xy 0.13716 0.82804) (xy 0.11684 0.85344)
						(xy 0.09144 0.87376) (xy 0.0635 0.889) (xy 0.03175 0.89916)
					)
					(width 0)
					(fill yes)
				)
			)
		)
		(pad "178" smd custom
			(at 23.850092 -4.106672)
			(size 0.1143 0.1143)
			(layers "F.Cu" "F.Mask" "F.Paste")
			(net "GND")
			(options
				(clearance outline)
				(anchor circle)
			)
			(primitives
				(gr_poly
					(pts
						(xy 0 0.9017) (xy -0.03175 0.89916) (xy -0.0635 0.889) (xy -0.09144 0.87376) (xy -0.11684 0.85344)
						(xy -0.13716 0.82804) (xy -0.1524 0.8001) (xy -0.16256 0.76835) (xy -0.1651 0.7366) (xy -0.1651 0.44958)
						(xy -0.17272 0.44196) (xy -0.19812 0.4064) (xy -0.2032 0.39624) (xy -0.20701 0.38735) (xy -0.21209 0.37719)
						(xy -0.2159 0.36703) (xy -0.21844 0.35687) (xy -0.22225 0.34544) (xy -0.22352 0.33528) (xy -0.22606 0.32512)
						(xy -0.22733 0.31369) (xy -0.22733 0.30353) (xy -0.2286 0.2921) (xy -0.22733 0.28067) (xy -0.22733 0.27051)
						(xy -0.22606 0.25908) (xy -0.22352 0.24892) (xy -0.22225 0.23876) (xy -0.21844 0.22733) (xy -0.2159 0.21717)
						(xy -0.21209 0.20701) (xy -0.20701 0.19685) (xy -0.2032 0.18796) (xy -0.19812 0.1778) (xy -0.17272 0.14224)
						(xy -0.1651 0.13462) (xy -0.1651 -0.7366) (xy -0.16256 -0.76835) (xy -0.1524 -0.8001) (xy -0.13716 -0.82804)
						(xy -0.11684 -0.85344) (xy -0.09144 -0.87376) (xy -0.0635 -0.889) (xy -0.03175 -0.89916) (xy 0 -0.9017)
						(xy 0.03175 -0.89916) (xy 0.0635 -0.889) (xy 0.09144 -0.87376) (xy 0.11684 -0.85344) (xy 0.13716 -0.82804)
						(xy 0.1524 -0.8001) (xy 0.16256 -0.76835) (xy 0.1651 -0.7366) (xy 0.1651 0.13462) (xy 0.17272 0.14224)
						(xy 0.19812 0.1778) (xy 0.2032 0.18796) (xy 0.20701 0.19685) (xy 0.21209 0.20701) (xy 0.2159 0.21717)
						(xy 0.21844 0.22733) (xy 0.22225 0.23876) (xy 0.22352 0.24892) (xy 0.22606 0.25908) (xy 0.22733 0.27051)
						(xy 0.22733 0.28067) (xy 0.2286 0.2921) (xy 0.22733 0.30353) (xy 0.22733 0.31369) (xy 0.22606 0.32512)
						(xy 0.22352 0.33528) (xy 0.22225 0.34544) (xy 0.21844 0.35687) (xy 0.2159 0.36703) (xy 0.21209 0.37719)
						(xy 0.20701 0.38735) (xy 0.2032 0.39624) (xy 0.19812 0.4064) (xy 0.17272 0.44196) (xy 0.1651 0.44958)
						(xy 0.1651 0.7366) (xy 0.16256 0.76835) (xy 0.1524 0.8001) (xy 0.13716 0.82804) (xy 0.11684 0.85344)
						(xy 0.09144 0.87376) (xy 0.0635 0.889) (xy 0.03175 0.89916)
					)
					(width 0)
					(fill yes)
				)
			)
		)
		(pad "179" smd custom
			(at 24.150066 4.106672)
			(size 0.1143 0.1143)
			(layers "F.Cu" "F.Mask" "F.Paste")
			(net "M_B_DQ55")
			(options
				(clearance outline)
				(anchor circle)
			)
			(primitives
				(gr_poly
					(pts
						(xy 0 0.9017) (xy -0.03175 0.89916) (xy -0.0635 0.889) (xy -0.09144 0.87376) (xy -0.11684 0.85344)
						(xy -0.13716 0.82804) (xy -0.1524 0.8001) (xy -0.16256 0.76835) (xy -0.1651 0.7366) (xy -0.1651 0.11938)
						(xy -0.17272 0.11176) (xy -0.19812 0.0762) (xy -0.2032 0.06604) (xy -0.20701 0.05715) (xy -0.21209 0.04699)
						(xy -0.2159 0.03683) (xy -0.21844 0.02667) (xy -0.22225 0.01524) (xy -0.22352 0.00508) (xy -0.22606 -0.00508)
						(xy -0.22733 -0.01651) (xy -0.22733 -0.02667) (xy -0.2286 -0.0381) (xy -0.22733 -0.04953) (xy -0.22733 -0.05969)
						(xy -0.22606 -0.07112) (xy -0.22352 -0.08128) (xy -0.22225 -0.09144) (xy -0.21844 -0.10287) (xy -0.2159 -0.11303)
						(xy -0.21209 -0.12319) (xy -0.20701 -0.13335) (xy -0.2032 -0.14224) (xy -0.19812 -0.1524) (xy -0.17272 -0.18796)
						(xy -0.1651 -0.19558) (xy -0.1651 -0.7366) (xy -0.16256 -0.76835) (xy -0.1524 -0.8001) (xy -0.13716 -0.82804)
						(xy -0.11684 -0.85344) (xy -0.09144 -0.87376) (xy -0.0635 -0.889) (xy -0.03175 -0.89916) (xy 0 -0.9017)
						(xy 0.03175 -0.89916) (xy 0.0635 -0.889) (xy 0.09144 -0.87376) (xy 0.11684 -0.85344) (xy 0.13716 -0.82804)
						(xy 0.1524 -0.8001) (xy 0.16256 -0.76835) (xy 0.1651 -0.7366) (xy 0.1651 -0.19685) (xy 0.17272 -0.18923)
						(xy 0.17907 -0.18034) (xy 0.18669 -0.17145) (xy 0.19177 -0.16256) (xy 0.19812 -0.15367) (xy 0.20828 -0.13335)
						(xy 0.21971 -0.10287) (xy 0.22225 -0.09271) (xy 0.22479 -0.08128) (xy 0.22606 -0.07112) (xy 0.2286 -0.05969)
						(xy 0.2286 -0.01651) (xy 0.22606 -0.00508) (xy 0.22479 0.00508) (xy 0.22225 0.01651) (xy 0.21971 0.02667)
						(xy 0.20828 0.05715) (xy 0.19812 0.07747) (xy 0.19177 0.08636) (xy 0.18669 0.09525) (xy 0.17907 0.10414)
						(xy 0.17272 0.11303) (xy 0.1651 0.12065) (xy 0.1651 0.7366) (xy 0.16256 0.76835) (xy 0.1524 0.8001)
						(xy 0.13716 0.82804) (xy 0.11684 0.85344) (xy 0.09144 0.87376) (xy 0.0635 0.889) (xy 0.03175 0.89916)
					)
					(width 0)
					(fill yes)
				)
			)
		)
		(pad "180" smd custom
			(at 24.45004 -4.106672)
			(size 0.1143 0.1143)
			(layers "F.Cu" "F.Mask" "F.Paste")
			(net "M_B_DQ56")
			(options
				(clearance outline)
				(anchor circle)
			)
			(primitives
				(gr_poly
					(pts
						(xy 0 0.9017) (xy -0.03175 0.89916) (xy -0.0635 0.889) (xy -0.09144 0.87376) (xy -0.11684 0.85344)
						(xy -0.13716 0.82804) (xy -0.1524 0.8001) (xy -0.16256 0.76835) (xy -0.1651 0.7366) (xy -0.1651 0.19685)
						(xy -0.17272 0.18923) (xy -0.17907 0.18034) (xy -0.18669 0.17145) (xy -0.19177 0.16256) (xy -0.19812 0.15367)
						(xy -0.20828 0.13335) (xy -0.21971 0.10287) (xy -0.22225 0.09271) (xy -0.22479 0.08128) (xy -0.22606 0.07112)
						(xy -0.2286 0.05969) (xy -0.2286 0.01651) (xy -0.22606 0.00508) (xy -0.22479 -0.00508) (xy -0.22225 -0.01651)
						(xy -0.21971 -0.02667) (xy -0.20828 -0.05715) (xy -0.19812 -0.07747) (xy -0.19177 -0.08636) (xy -0.18669 -0.09525)
						(xy -0.17907 -0.10414) (xy -0.17272 -0.11303) (xy -0.1651 -0.12065) (xy -0.1651 -0.7366) (xy -0.16256 -0.76835)
						(xy -0.1524 -0.8001) (xy -0.13716 -0.82804) (xy -0.11684 -0.85344) (xy -0.09144 -0.87376) (xy -0.0635 -0.889)
						(xy -0.03175 -0.89916) (xy 0 -0.9017) (xy 0.03175 -0.89916) (xy 0.0635 -0.889) (xy 0.09144 -0.87376)
						(xy 0.11684 -0.85344) (xy 0.13716 -0.82804) (xy 0.1524 -0.8001) (xy 0.16256 -0.76835) (xy 0.1651 -0.7366)
						(xy 0.1651 -0.11938) (xy 0.17272 -0.11176) (xy 0.19812 -0.0762) (xy 0.2032 -0.06604) (xy 0.20701 -0.05715)
						(xy 0.21209 -0.04699) (xy 0.2159 -0.03683) (xy 0.21844 -0.02667) (xy 0.22225 -0.01524) (xy 0.22352 -0.00508)
						(xy 0.22606 0.00508) (xy 0.22733 0.01651) (xy 0.22733 0.02667) (xy 0.2286 0.0381) (xy 0.22733 0.04953)
						(xy 0.22733 0.05969) (xy 0.22606 0.07112) (xy 0.22352 0.08128) (xy 0.22225 0.09144) (xy 0.21844 0.10287)
						(xy 0.2159 0.11303) (xy 0.21209 0.12319) (xy 0.20701 0.13335) (xy 0.2032 0.14224) (xy 0.19812 0.1524)
						(xy 0.17272 0.18796) (xy 0.1651 0.19558) (xy 0.1651 0.7366) (xy 0.16256 0.76835) (xy 0.1524 0.8001)
						(xy 0.13716 0.82804) (xy 0.11684 0.85344) (xy 0.09144 0.87376) (xy 0.0635 0.889) (xy 0.03175 0.89916)
					)
					(width 0)
					(fill yes)
				)
			)
		)
		(pad "181" smd custom
			(at 24.750014 4.106672)
			(size 0.1143 0.1143)
			(layers "F.Cu" "F.Mask" "F.Paste")
			(net "GND")
			(options
				(clearance outline)
				(anchor circle)
			)
			(primitives
				(gr_poly
					(pts
						(xy 0 0.9017) (xy -0.03175 0.89916) (xy -0.0635 0.889) (xy -0.09144 0.87376) (xy -0.11684 0.85344)
						(xy -0.13716 0.82804) (xy -0.1524 0.8001) (xy -0.16256 0.76835) (xy -0.1651 0.7366) (xy -0.1651 -0.13462)
						(xy -0.17272 -0.14224) (xy -0.19812 -0.1778) (xy -0.2032 -0.18796) (xy -0.20701 -0.19685) (xy -0.21209 -0.20701)
						(xy -0.2159 -0.21717) (xy -0.21844 -0.22733) (xy -0.22225 -0.23876) (xy -0.22352 -0.24892) (xy -0.22606 -0.25908)
						(xy -0.22733 -0.27051) (xy -0.22733 -0.28067) (xy -0.2286 -0.2921) (xy -0.22733 -0.30353) (xy -0.22733 -0.31369)
						(xy -0.22606 -0.32512) (xy -0.22352 -0.33528) (xy -0.22225 -0.34544) (xy -0.21844 -0.35687) (xy -0.2159 -0.36703)
						(xy -0.21209 -0.37719) (xy -0.20701 -0.38735) (xy -0.2032 -0.39624) (xy -0.19812 -0.4064) (xy -0.17272 -0.44196)
						(xy -0.1651 -0.44958) (xy -0.1651 -0.7366) (xy -0.16256 -0.76835) (xy -0.1524 -0.8001) (xy -0.13716 -0.82804)
						(xy -0.11684 -0.85344) (xy -0.09144 -0.87376) (xy -0.0635 -0.889) (xy -0.03175 -0.89916) (xy 0 -0.9017)
						(xy 0.03175 -0.89916) (xy 0.0635 -0.889) (xy 0.09144 -0.87376) (xy 0.11684 -0.85344) (xy 0.13716 -0.82804)
						(xy 0.1524 -0.8001) (xy 0.16256 -0.76835) (xy 0.1651 -0.7366) (xy 0.1651 -0.44958) (xy 0.17272 -0.44196)
						(xy 0.19812 -0.4064) (xy 0.2032 -0.39624) (xy 0.20701 -0.38735) (xy 0.21209 -0.37719) (xy 0.2159 -0.36703)
						(xy 0.21844 -0.35687) (xy 0.22225 -0.34544) (xy 0.22352 -0.33528) (xy 0.22606 -0.32512) (xy 0.22733 -0.31369)
						(xy 0.22733 -0.30353) (xy 0.2286 -0.2921) (xy 0.22733 -0.28067) (xy 0.22733 -0.27051) (xy 0.22606 -0.25908)
						(xy 0.22352 -0.24892) (xy 0.22225 -0.23876) (xy 0.21844 -0.22733) (xy 0.2159 -0.21717) (xy 0.21209 -0.20701)
						(xy 0.20701 -0.19685) (xy 0.2032 -0.18796) (xy 0.19812 -0.1778) (xy 0.17272 -0.14224) (xy 0.1651 -0.13462)
						(xy 0.1651 0.7366) (xy 0.16256 0.76835) (xy 0.1524 0.8001) (xy 0.13716 0.82804) (xy 0.11684 0.85344)
						(xy 0.09144 0.87376) (xy 0.0635 0.889) (xy 0.03175 0.89916)
					)
					(width 0)
					(fill yes)
				)
			)
		)
	)
)
